# S9S_MB_2U (Grand Teton) — schematic netlist excerpt (pin names and nets, part order shuffled) for the footprints in the layout excerpt that follows; sources: Cadence DE-HDL packaged netlist, KiCad conversion of 03242023_DA0F0TMBIJ0_F0T_Motherboard_J_brd_V01_OCP.brd

R4167  Q_RES  4.7K 5% CHIP  pkg 0402LF  page 145 : A = P3V3_AUX ; B = GPU_3V3IO_RSVD1_ISO
C440  Q_CAP  22UF 4V 20% X6S  pkg C0402  page 77 : A = PVCCINFAON_CPU1 ; B = GND

(kicad_pcb
	(version 20260206)
	(generator "pcbnew")
	(generator_version "10.0")
	(general
		(thickness 1.6)
		(legacy_teardrops no)
	)
	(paper "A4")
	(title_block
		(title "03242023_DA0F0TMBIJ0_F0T_Motherboard_J_brd_V01_OCP.brd")
		(comment 1 "Grand Teton / footprints 1134-1135 of 6105")
	)
	(layers
		(0 "F.Cu" signal "TOP")
		(4 "In1.Cu" signal "GND")
		(6 "In2.Cu" signal "IN1")
		(8 "In3.Cu" signal "GND1")
		(10 "In4.Cu" signal "IN2")
		(12 "In5.Cu" signal "GND2")
		(14 "In6.Cu" signal "IN3")
		(16 "In7.Cu" signal "GND3")
		(18 "In8.Cu" signal "VCC")
		(20 "In9.Cu" signal "VCC1")
		(22 "In10.Cu" signal "GND4")
		(24 "In11.Cu" signal "IN4")
		(26 "In12.Cu" signal "GND5")
		(28 "In13.Cu" signal "IN5")
		(30 "In14.Cu" signal "GND6")
		(32 "In15.Cu" signal "IN6")
		(34 "In16.Cu" signal "GND7")
		(2 "B.Cu" signal "BOTTOM")
		(9 "F.Adhes" user "F.Adhesive")
		(11 "B.Adhes" user "B.Adhesive")
		(13 "F.Paste" user "Package Geometry/Pastemask Top")
		(15 "B.Paste" user "Package Geometry/Pastemask Bottom")
		(5 "F.SilkS" user "Ref Des/Silkscreen Top")
		(7 "B.SilkS" user "Ref Des/Silkscreen Bottom")
		(1 "F.Mask" user "Board Geometry/Soldermask Top")
		(3 "B.Mask" user "Board Geometry/Soldermask Bottom")
		(17 "Dwgs.User" user "User.Drawings")
		(19 "Cmts.User" user "User.Comments")
		(21 "Eco1.User" user "User.Eco1")
		(23 "Eco2.User" user "User.Eco2")
		(25 "Edge.Cuts" user "Board Geometry/Outline")
		(27 "Margin" user)
		(31 "F.CrtYd" user "Package Geometry/Place Bound Top")
		(29 "B.CrtYd" user "Package Geometry/Place Bound Bottom")
		(35 "F.Fab" user "Ref Des/Assembly Top")
		(33 "B.Fab" user "Ref Des/Assembly Bottom")
	)
	(footprint ""
		(layer "F.Cu")
		(at 360.383582 -385.17449)
		(property "Reference" "R4167"
			(at 0 0 0)
			(layer "F.SilkS")
			(hide yes)
			(effects
				(font
					(size 1.27 1.27)
				)
			)
		)
		(property "Value" ""
			(at 0 0 0)
			(layer "F.Fab")
			(effects
				(font
					(size 1.27 1.27)
				)
			)
		)
		(duplicate_pad_numbers_are_jumpers no)
		(fp_line
			(start -0.7874 -0.4064)
			(end 0.7874 -0.4064)
			(stroke
				(width 0.1524)
				(type default)
			)
			(layer "F.SilkS")
		)
		(fp_line
			(start -0.7874 0.4064)
			(end -0.7874 -0.4064)
			(stroke
				(width 0.1524)
				(type default)
			)
			(layer "F.SilkS")
		)
		(fp_line
			(start 0.7874 -0.4064)
			(end 0.7874 0.4064)
			(stroke
				(width 0.1524)
				(type default)
			)
			(layer "F.SilkS")
		)
		(fp_line
			(start 0.7874 0.4064)
			(end -0.7874 0.4064)
			(stroke
				(width 0.1524)
				(type default)
			)
			(layer "F.SilkS")
		)
		(fp_line
			(start -0.67945 -0.305054)
			(end -0.12065 -0.305054)
			(stroke
				(width 0.1)
				(type default)
			)
			(layer "F.Fab")
		)
		(fp_line
			(start -0.67945 0.3048)
			(end -0.67945 -0.305054)
			(stroke
				(width 0.1)
				(type default)
			)
			(layer "F.Fab")
		)
		(fp_line
			(start -0.12065 -0.305054)
			(end -0.12065 -0.2794)
			(stroke
				(width 0.1)
				(type default)
			)
			(layer "F.Fab")
		)
		(fp_line
			(start -0.12065 -0.2794)
			(end 0.12065 -0.2794)
			(stroke
				(width 0.1)
				(type default)
			)
			(layer "F.Fab")
		)
		(fp_line
			(start -0.12065 0.2794)
			(end -0.12065 0.3048)
			(stroke
				(width 0.1)
				(type default)
			)
			(layer "F.Fab")
		)
		(fp_line
			(start -0.12065 0.3048)
			(end -0.67945 0.3048)
			(stroke
				(width 0.1)
				(type default)
			)
			(layer "F.Fab")
		)
		(fp_line
			(start 0.120396 0.2794)
			(end -0.12065 0.2794)
			(stroke
				(width 0.1)
				(type default)
			)
			(layer "F.Fab")
		)
		(fp_line
			(start 0.120396 0.3048)
			(end 0.120396 0.2794)
			(stroke
				(width 0.1)
				(type default)
			)
			(layer "F.Fab")
		)
		(fp_line
			(start 0.12065 -0.3048)
			(end 0.67945 -0.3048)
			(stroke
				(width 0.1)
				(type default)
			)
			(layer "F.Fab")
		)
		(fp_line
			(start 0.12065 -0.2794)
			(end 0.12065 -0.3048)
			(stroke
				(width 0.1)
				(type default)
			)
			(layer "F.Fab")
		)
		(fp_line
			(start 0.67945 -0.3048)
			(end 0.67945 0.3048)
			(stroke
				(width 0.1)
				(type default)
			)
			(layer "F.Fab")
		)
		(fp_line
			(start 0.67945 0.3048)
			(end 0.120396 0.3048)
			(stroke
				(width 0.1)
				(type default)
			)
			(layer "F.Fab")
		)
		(pad "1" smd circle
			(at -0.40005 0)
			(size 0 0)
			(layers "F.Cu" "F.Mask" "F.Paste")
			(net "P3V3_AUX")
		)
		(pad "2" smd circle
			(at 0.40005 0)
			(size 0 0)
			(layers "F.Cu" "F.Mask" "F.Paste")
			(net "GPU_3V3IO_RSVD1_ISO")
		)
	)
	(footprint ""
		(layer "F.Cu")
		(at 119.508016 -238.162592 90)
		(property "Reference" "C440"
			(at 0 0 90)
			(layer "F.SilkS")
			(hide yes)
			(effects
				(font
					(size 1.27 1.27)
				)
			)
		)
		(property "Value" ""
			(at 0 0 90)
			(layer "F.Fab")
			(effects
				(font
					(size 1.27 1.27)
				)
			)
		)
		(duplicate_pad_numbers_are_jumpers no)
		(fp_line
			(start 0.7874 -0.4064)
			(end 0.7874 0.4064)
			(stroke
				(width 0.1524)
				(type default)
			)
			(layer "F.SilkS")
		)
		(fp_line
			(start -0.7874 -0.4064)
			(end 0.7874 -0.4064)
			(stroke
				(width 0.1524)
				(type default)
			)
			(layer "F.SilkS")
		)
		(fp_line
			(start 0.7874 0.4064)
			(end -0.7874 0.4064)
			(stroke
				(width 0.1524)
				(type default)
			)
			(layer "F.SilkS")
		)
		(fp_line
			(start -0.7874 0.4064)
			(end -0.7874 -0.4064)
			(stroke
				(width 0.1524)
				(type default)
			)
			(layer "F.SilkS")
		)
		(fp_line
			(start -0.12065 -0.305054)
			(end -0.12065 -0.2794)
			(stroke
				(width 0.1)
				(type default)
			)
			(layer "F.Fab")
		)
		(fp_line
			(start -0.67945 -0.305054)
			(end -0.12065 -0.305054)
			(stroke
				(width 0.1)
				(type default)
			)
			(layer "F.Fab")
		)
		(fp_line
			(start 0.67945 -0.3048)
			(end 0.67945 0.3048)
			(stroke
				(width 0.1)
				(type default)
			)
			(layer "F.Fab")
		)
		(fp_line
			(start 0.12065 -0.3048)
			(end 0.67945 -0.3048)
			(stroke
				(width 0.1)
				(type default)
			)
			(layer "F.Fab")
		)
		(fp_line
			(start 0.12065 -0.2794)
			(end 0.12065 -0.3048)
			(stroke
				(width 0.1)
				(type default)
			)
			(layer "F.Fab")
		)
		(fp_line
			(start -0.12065 -0.2794)
			(end 0.12065 -0.2794)
			(stroke
				(width 0.1)
				(type default)
			)
			(layer "F.Fab")
		)
		(fp_line
			(start 0.120396 0.2794)
			(end -0.12065 0.2794)
			(stroke
				(width 0.1)
				(type default)
			)
			(layer "F.Fab")
		)
		(fp_line
			(start -0.12065 0.2794)
			(end -0.12065 0.3048)
			(stroke
				(width 0.1)
				(type default)
			)
			(layer "F.Fab")
		)
		(fp_line
			(start 0.67945 0.3048)
			(end 0.120396 0.3048)
			(stroke
				(width 0.1)
				(type default)
			)
			(layer "F.Fab")
		)
		(fp_line
			(start 0.120396 0.3048)
			(end 0.120396 0.2794)
			(stroke
				(width 0.1)
				(type default)
			)
			(layer "F.Fab")
		)
		(fp_line
			(start -0.12065 0.3048)
			(end -0.67945 0.3048)
			(stroke
				(width 0.1)
				(type default)
			)
			(layer "F.Fab")
		)
		(fp_line
			(start -0.67945 0.3048)
			(end -0.67945 -0.305054)
			(stroke
				(width 0.1)
				(type default)
			)
			(layer "F.Fab")
		)
		(pad "1" smd circle
			(at -0.40005 0 90)
			(size 0 0)
			(layers "F.Cu" "F.Mask" "F.Paste")
			(net "PVCCINFAON_CPU1")
		)
		(pad "2" smd circle
			(at 0.40005 0 90)
			(size 0 0)
			(layers "F.Cu" "F.Mask" "F.Paste")
			(net "GND")
		)
	)
)
